# T6G (Grand Teton) — schematic netlist excerpt (pin names and nets, part order shuffled) for the footprints in the layout excerpt that follows; sources: Cadence DE-HDL packaged netlist, KiCad conversion of 04192023_DAF0TMB3IC0_F0TG_MB_C_brd_V02_OCP.brd

R3590  Q_RES  33.2 1% CHIP  pkg 0402LF  page 251 : A = SMB_INA230_3V3AUX_SCL ; B = SMB_INA230_3_3V3AUX_SCL_R
PC6638_2  Q_CAP  22UF 16V 20% X6S  pkg C0805  page 365 : A = SW_P12V_AUX_P0V9_RETIMER_CPU1_FLT ; B = GND
R3287  Q_RES  1K 1% EMPTY  pkg 0402LF  page 111 : A = FM_P2E_SWB ; B = GND

(kicad_pcb
	(version 20260206)
	(generator "pcbnew")
	(generator_version "10.0")
	(general
		(thickness 1.6)
		(legacy_teardrops no)
	)
	(paper "A4")
	(title_block
		(title "04192023_DAF0TMB3IC0_F0TG_MB_C_brd_V02_OCP.brd")
		(comment 1 "Grand Teton / footprints 2575-2577 of 8354")
	)
	(layers
		(0 "F.Cu" signal "TOP")
		(4 "In1.Cu" signal "GND")
		(6 "In2.Cu" signal "IN1")
		(8 "In3.Cu" signal "GND1")
		(10 "In4.Cu" signal "IN2")
		(12 "In5.Cu" signal "GND2")
		(14 "In6.Cu" signal "IN3")
		(16 "In7.Cu" signal "GND3")
		(18 "In8.Cu" signal "VCC")
		(20 "In9.Cu" signal "VCC1")
		(22 "In10.Cu" signal "GND4")
		(24 "In11.Cu" signal "IN4")
		(26 "In12.Cu" signal "GND5")
		(28 "In13.Cu" signal "IN5")
		(30 "In14.Cu" signal "GND6")
		(32 "In15.Cu" signal "IN6")
		(34 "In16.Cu" signal "GND7")
		(2 "B.Cu" signal "BOTTOM")
		(9 "F.Adhes" user "F.Adhesive")
		(11 "B.Adhes" user "B.Adhesive")
		(13 "F.Paste" user "Package Geometry/Pastemask Top")
		(15 "B.Paste" user "Package Geometry/Pastemask Bottom")
		(5 "F.SilkS" user "Ref Des/Silkscreen Top")
		(7 "B.SilkS" user "Ref Des/Silkscreen Bottom")
		(1 "F.Mask" user "Board Geometry/Soldermask Top")
		(3 "B.Mask" user "Board Geometry/Soldermask Bottom")
		(17 "Dwgs.User" user "User.Drawings")
		(19 "Cmts.User" user "User.Comments")
		(21 "Eco1.User" user "User.Eco1")
		(23 "Eco2.User" user "User.Eco2")
		(25 "Edge.Cuts" user "Board Geometry/Outline")
		(27 "Margin" user)
		(31 "F.CrtYd" user "Package Geometry/Place Bound Top")
		(29 "B.CrtYd" user "Package Geometry/Place Bound Bottom")
		(35 "F.Fab" user "Ref Des/Assembly Top")
		(33 "B.Fab" user "Ref Des/Assembly Bottom")
	)
	(footprint ""
		(layer "F.Cu")
		(at 35.395662 -429.790098 90)
		(property "Reference" "R3287"
			(at 0 0 90)
			(layer "F.SilkS")
			(hide yes)
			(effects
				(font
					(size 1.27 1.27)
				)
			)
		)
		(property "Value" ""
			(at 0 0 90)
			(layer "F.Fab")
			(effects
				(font
					(size 1.27 1.27)
				)
			)
		)
		(duplicate_pad_numbers_are_jumpers no)
		(fp_line
			(start 0.7874 -0.4064)
			(end 0.7874 0.4064)
			(stroke
				(width 0.1524)
				(type default)
			)
			(layer "F.SilkS")
		)
		(fp_line
			(start -0.7874 -0.4064)
			(end 0.7874 -0.4064)
			(stroke
				(width 0.1524)
				(type default)
			)
			(layer "F.SilkS")
		)
		(fp_line
			(start 0.7874 0.4064)
			(end -0.7874 0.4064)
			(stroke
				(width 0.1524)
				(type default)
			)
			(layer "F.SilkS")
		)
		(fp_line
			(start -0.7874 0.4064)
			(end -0.7874 -0.4064)
			(stroke
				(width 0.1524)
				(type default)
			)
			(layer "F.SilkS")
		)
		(fp_line
			(start -0.12065 -0.305054)
			(end -0.12065 -0.2794)
			(stroke
				(width 0.1)
				(type default)
			)
			(layer "F.Fab")
		)
		(fp_line
			(start -0.67945 -0.305054)
			(end -0.12065 -0.305054)
			(stroke
				(width 0.1)
				(type default)
			)
			(layer "F.Fab")
		)
		(fp_line
			(start 0.67945 -0.3048)
			(end 0.67945 0.3048)
			(stroke
				(width 0.1)
				(type default)
			)
			(layer "F.Fab")
		)
		(fp_line
			(start 0.12065 -0.3048)
			(end 0.67945 -0.3048)
			(stroke
				(width 0.1)
				(type default)
			)
			(layer "F.Fab")
		)
		(fp_line
			(start 0.12065 -0.2794)
			(end 0.12065 -0.3048)
			(stroke
				(width 0.1)
				(type default)
			)
			(layer "F.Fab")
		)
		(fp_line
			(start -0.12065 -0.2794)
			(end 0.12065 -0.2794)
			(stroke
				(width 0.1)
				(type default)
			)
			(layer "F.Fab")
		)
		(fp_line
			(start 0.120396 0.2794)
			(end -0.12065 0.2794)
			(stroke
				(width 0.1)
				(type default)
			)
			(layer "F.Fab")
		)
		(fp_line
			(start -0.12065 0.2794)
			(end -0.12065 0.3048)
			(stroke
				(width 0.1)
				(type default)
			)
			(layer "F.Fab")
		)
		(fp_line
			(start 0.67945 0.3048)
			(end 0.120396 0.3048)
			(stroke
				(width 0.1)
				(type default)
			)
			(layer "F.Fab")
		)
		(fp_line
			(start 0.120396 0.3048)
			(end 0.120396 0.2794)
			(stroke
				(width 0.1)
				(type default)
			)
			(layer "F.Fab")
		)
		(fp_line
			(start -0.12065 0.3048)
			(end -0.67945 0.3048)
			(stroke
				(width 0.1)
				(type default)
			)
			(layer "F.Fab")
		)
		(fp_line
			(start -0.67945 0.3048)
			(end -0.67945 -0.305054)
			(stroke
				(width 0.1)
				(type default)
			)
			(layer "F.Fab")
		)
		(pad "1" smd circle
			(at -0.40005 0 90)
			(size 0 0)
			(layers "F.Cu" "F.Mask" "F.Paste")
			(net "FM_P2E_SWB")
		)
		(pad "2" smd circle
			(at 0.40005 0 90)
			(size 0 0)
			(layers "F.Cu" "F.Mask" "F.Paste")
			(net "GND")
		)
	)
	(footprint ""
		(layer "F.Cu")
		(at 154.633676 -48.961294 -90)
		(property "Reference" "R3590"
			(at 0 0 270)
			(layer "F.SilkS")
			(hide yes)
			(effects
				(font
					(size 1.27 1.27)
				)
			)
		)
		(property "Value" ""
			(at 0 0 270)
			(layer "F.Fab")
			(effects
				(font
					(size 1.27 1.27)
				)
			)
		)
		(duplicate_pad_numbers_are_jumpers no)
		(fp_line
			(start -0.7874 0.4064)
			(end -0.7874 -0.4064)
			(stroke
				(width 0.1524)
				(type default)
			)
			(layer "F.SilkS")
		)
		(fp_line
			(start 0.7874 0.4064)
			(end -0.7874 0.4064)
			(stroke
				(width 0.1524)
				(type default)
			)
			(layer "F.SilkS")
		)
		(fp_line
			(start -0.7874 -0.4064)
			(end 0.7874 -0.4064)
			(stroke
				(width 0.1524)
				(type default)
			)
			(layer "F.SilkS")
		)
		(fp_line
			(start 0.7874 -0.4064)
			(end 0.7874 0.4064)
			(stroke
				(width 0.1524)
				(type default)
			)
			(layer "F.SilkS")
		)
		(fp_line
			(start -0.67945 0.3048)
			(end -0.67945 -0.305054)
			(stroke
				(width 0.1)
				(type default)
			)
			(layer "F.Fab")
		)
		(fp_line
			(start -0.12065 0.3048)
			(end -0.67945 0.3048)
			(stroke
				(width 0.1)
				(type default)
			)
			(layer "F.Fab")
		)
		(fp_line
			(start 0.120396 0.3048)
			(end 0.120396 0.2794)
			(stroke
				(width 0.1)
				(type default)
			)
			(layer "F.Fab")
		)
		(fp_line
			(start 0.67945 0.3048)
			(end 0.120396 0.3048)
			(stroke
				(width 0.1)
				(type default)
			)
			(layer "F.Fab")
		)
		(fp_line
			(start -0.12065 0.2794)
			(end -0.12065 0.3048)
			(stroke
				(width 0.1)
				(type default)
			)
			(layer "F.Fab")
		)
		(fp_line
			(start 0.120396 0.2794)
			(end -0.12065 0.2794)
			(stroke
				(width 0.1)
				(type default)
			)
			(layer "F.Fab")
		)
		(fp_line
			(start -0.12065 -0.2794)
			(end 0.12065 -0.2794)
			(stroke
				(width 0.1)
				(type default)
			)
			(layer "F.Fab")
		)
		(fp_line
			(start 0.12065 -0.2794)
			(end 0.12065 -0.3048)
			(stroke
				(width 0.1)
				(type default)
			)
			(layer "F.Fab")
		)
		(fp_line
			(start 0.12065 -0.3048)
			(end 0.67945 -0.3048)
			(stroke
				(width 0.1)
				(type default)
			)
			(layer "F.Fab")
		)
		(fp_line
			(start 0.67945 -0.3048)
			(end 0.67945 0.3048)
			(stroke
				(width 0.1)
				(type default)
			)
			(layer "F.Fab")
		)
		(fp_line
			(start -0.67945 -0.305054)
			(end -0.12065 -0.305054)
			(stroke
				(width 0.1)
				(type default)
			)
			(layer "F.Fab")
		)
		(fp_line
			(start -0.12065 -0.305054)
			(end -0.12065 -0.2794)
			(stroke
				(width 0.1)
				(type default)
			)
			(layer "F.Fab")
		)
		(pad "1" smd circle
			(at -0.40005 0 270)
			(size 0 0)
			(layers "F.Cu" "F.Mask" "F.Paste")
			(net "SMB_INA230_3V3AUX_SCL")
		)
		(pad "2" smd circle
			(at 0.40005 0 270)
			(size 0 0)
			(layers "F.Cu" "F.Mask" "F.Paste")
			(net "SMB_INA230_3_3V3AUX_SCL_R")
		)
	)
	(footprint ""
		(layer "F.Cu")
		(at 18.076672 -396.076678 180)
		(property "Reference" "PC6638_2"
			(at 0 0 180)
			(layer "F.SilkS")
			(hide yes)
			(effects
				(font
					(size 1.27 1.27)
				)
			)
		)
		(property "Value" ""
			(at 0 0 180)
			(layer "F.Fab")
			(effects
				(font
					(size 1.27 1.27)
				)
			)
		)
		(duplicate_pad_numbers_are_jumpers no)
		(fp_line
			(start 1.524 0.762)
			(end -1.524 0.762)
			(stroke
				(width 0.1524)
				(type default)
			)
			(layer "F.SilkS")
		)
		(fp_line
			(start 1.524 -0.762)
			(end 1.524 0.762)
			(stroke
				(width 0.1524)
				(type default)
			)
			(layer "F.SilkS")
		)
		(fp_line
			(start -1.524 0.762)
			(end -1.524 -0.762)
			(stroke
				(width 0.1524)
				(type default)
			)
			(layer "F.SilkS")
		)
		(fp_line
			(start -1.524 -0.762)
			(end 1.524 -0.762)
			(stroke
				(width 0.1524)
				(type default)
			)
			(layer "F.SilkS")
		)
		(fp_line
			(start 1.1049 0.724916)
			(end 1.1049 -0.724916)
			(stroke
				(width 0.1)
				(type default)
			)
			(layer "F.Fab")
		)
		(fp_line
			(start 1.1049 -0.724916)
			(end -1.1049 -0.724916)
			(stroke
				(width 0.1)
				(type default)
			)
			(layer "F.Fab")
		)
		(fp_line
			(start -1.1049 0.724916)
			(end 1.1049 0.724916)
			(stroke
				(width 0.1)
				(type default)
			)
			(layer "F.Fab")
		)
		(fp_line
			(start -1.1049 -0.724916)
			(end -1.1049 0.724916)
			(stroke
				(width 0.1)
				(type default)
			)
			(layer "F.Fab")
		)
		(pad "1" smd rect
			(at -0.889 0)
			(size 1.016 1.27)
			(layers "F.Cu" "F.Mask" "F.Paste")
			(net "SW_P12V_AUX_P0V9_RETIMER_CPU1_FLT")
		)
		(pad "2" smd rect
			(at 0.889 0)
			(size 1.016 1.27)
			(layers "F.Cu" "F.Mask" "F.Paste")
			(net "GND")
		)
	)
)
